(kicad_pcb
	(version 20241229)
	(generator "pcbnew")
	(generator_version "9.0")
	(general
		(thickness 1.61)
		(legacy_teardrops no)
	)
	(paper "A3")
	(title_block
		(title "RDIMM DDR5 Tester")
		(date "2026-05-21")
		(rev "2.2.0")
		(company "Antmicro")
		(comment 9 "footprints 1-5 of 796")
	)
	(layers
		(0 "F.Cu" signal)
		(4 "In1.Cu" power)
		(6 "In2.Cu" mixed)
		(8 "In3.Cu" power)
		(10 "In4.Cu" mixed)
		(12 "In5.Cu" power)
		(14 "In6.Cu" mixed)
		(16 "In7.Cu" power)
		(18 "In8.Cu" power)
		(20 "In9.Cu" mixed)
		(22 "In10.Cu" power)
		(2 "B.Cu" signal)
		(9 "F.Adhes" user "F.Adhesive")
		(11 "B.Adhes" user "B.Adhesive")
		(13 "F.Paste" user)
		(15 "B.Paste" user)
		(5 "F.SilkS" user "F.Silkscreen")
		(7 "B.SilkS" user "B.Silkscreen")
		(1 "F.Mask" user)
		(3 "B.Mask" user)
		(17 "Dwgs.User" user "User.Drawings")
		(19 "Cmts.User" user "User.Comments")
		(21 "Eco1.User" user "User.Eco1")
		(23 "Eco2.User" user "User.Eco2")
		(25 "Edge.Cuts" user)
		(27 "Margin" user)
		(31 "F.CrtYd" user "F.Courtyard")
		(29 "B.CrtYd" user "B.Courtyard")
		(35 "F.Fab" user)
		(33 "B.Fab" user)
	)
	(footprint "antmicro-footprints:C_0402_1005Metric"
		(layer "F.Cu")
		(at 133.815 159.985 90)
		(descr "Capacitor SMD 0402")
		(tags "capacitor SMD 0402")
		(property "Reference" "C116"
			(at -1.065 2.385 90)
			(layer "F.SilkS")
			(effects
				(font
					(size 0.7 0.7)
					(thickness 0.15)
				)
				(justify left bottom)
			)
		)
		(property "Value" "C_4u7_0402"
			(at -1.022927 2.155213 90)
			(layer "F.Fab")
			(effects
				(font
					(size 0.7 0.7)
					(thickness 0.15)
				)
				(justify left bottom)
			)
		)
		(property "Datasheet" "https://www.murata.com/products/productdetail?partno=GRM155R61A475MEAA%23"
			(at 0 0 90)
			(layer "F.Fab")
			(hide yes)
			(effects
				(font
					(size 1.27 1.27)
					(thickness 0.15)
				)
			)
		)
		(property "Manufacturer" "Murata"
			(at 0 0 90)
			(unlocked yes)
			(layer "F.Fab")
			(hide yes)
			(effects
				(font
					(size 1 1)
					(thickness 0.15)
				)
			)
		)
		(property "MPN" "GRM155R61A475MEAAD"
			(at 0 0 90)
			(unlocked yes)
			(layer "F.Fab")
			(hide yes)
			(effects
				(font
					(size 1 1)
					(thickness 0.15)
				)
			)
		)
		(property "Val" "4u7"
			(at 0 0 90)
			(unlocked yes)
			(layer "F.Fab")
			(hide yes)
			(effects
				(font
					(size 1 1)
					(thickness 0.15)
				)
			)
		)
		(property "License" "Apache-2.0"
			(at 0 0 90)
			(unlocked yes)
			(layer "F.Fab")
			(hide yes)
			(effects
				(font
					(size 1 1)
					(thickness 0.15)
				)
			)
		)
		(property "Author" "Antmicro"
			(at 0 0 90)
			(unlocked yes)
			(layer "F.Fab")
			(hide yes)
			(effects
				(font
					(size 1 1)
					(thickness 0.15)
				)
			)
		)
		(property "Voltage" ""
			(at 0 0 90)
			(unlocked yes)
			(layer "F.Fab")
			(hide yes)
			(effects
				(font
					(size 1 1)
					(thickness 0.15)
				)
			)
		)
		(property "Dielectric" ""
			(at 0 0 90)
			(unlocked yes)
			(layer "F.Fab")
			(hide yes)
			(effects
				(font
					(size 1 1)
					(thickness 0.15)
				)
			)
		)
		(sheetname "/Debug FTDI + VNA/")
		(sheetfile "debug-ftdi.kicad_sch")
		(attr smd)
		(fp_rect
			(start -0.925 -0.47)
			(end 0.925 0.47)
			(stroke
				(width 0.05)
				(type default)
			)
			(fill no)
			(layer "F.CrtYd")
		)
		(fp_line
			(start 0.504 -0.25)
			(end 0.504 0.248)
			(stroke
				(width 0.15)
				(type solid)
			)
			(layer "F.Fab")
		)
		(fp_line
			(start -0.494 -0.25)
			(end 0.504 -0.25)
			(stroke
				(width 0.15)
				(type solid)
			)
			(layer "F.Fab")
		)
		(fp_line
			(start 0.504 0.248)
			(end -0.494 0.248)
			(stroke
				(width 0.15)
				(type solid)
			)
			(layer "F.Fab")
		)
		(fp_line
			(start -0.494 0.248)
			(end -0.494 -0.25)
			(stroke
				(width 0.15)
				(type solid)
			)
			(layer "F.Fab")
		)
		(fp_text user "License: Apache-2.0"
			(at -0.939 5.799 90)
			(layer "F.Fab")
			(effects
				(font
					(size 0.7 0.7)
					(thickness 0.15)
				)
				(justify left bottom)
			)
		)
		(fp_text user "${REFERENCE}"
			(at -0.939 4.599 90)
			(layer "F.Fab")
			(effects
				(font
					(size 0.7 0.7)
					(thickness 0.15)
				)
				(justify left bottom)
			)
		)
		(fp_text user "Author: Antmicro"
			(at -0.939 3.399 90)
			(layer "F.Fab")
			(effects
				(font
					(size 0.7 0.7)
					(thickness 0.15)
				)
				(justify left bottom)
			)
		)
		(pad "1" smd roundrect
			(at -0.48 0 90)
			(size 0.59 0.64)
			(layers "F.Cu" "F.Mask" "F.Paste")
			(roundrect_rratio 0.25)
			(net 5 "/Debug FTDI + VNA/FTDI_VPHY")
			(pintype "passive")
		)
		(pad "2" smd roundrect
			(at 0.48 0 90)
			(size 0.59 0.64)
			(layers "F.Cu" "F.Mask" "F.Paste")
			(roundrect_rratio 0.25)
			(net 1 "GND")
			(pintype "passive")
		)
	)
	(footprint "antmicro-footprints:C_0402_1005Metric"
		(layer "F.Cu")
		(at 138.396843 156.001328 90)
		(descr "Capacitor SMD 0402")
		(tags "capacitor SMD 0402")
		(property "Reference" "C123"
			(at 1.251328 0.503157 90)
			(layer "F.SilkS")
			(effects
				(font
					(size 0.7 0.7)
					(thickness 0.15)
				)
				(justify left bottom)
			)
		)
		(property "Value" "C_100n_0402"
			(at -1.022927 2.155213 90)
			(layer "F.Fab")
			(effects
				(font
					(size 0.7 0.7)
					(thickness 0.15)
				)
				(justify left bottom)
			)
		)
		(property "Datasheet" "https://www.murata.com/products/productdetail?partno=GRM155R61H104KE14%23"
			(at 0 0 90)
			(layer "F.Fab")
			(hide yes)
			(effects
				(font
					(size 1.27 1.27)
					(thickness 0.15)
				)
			)
		)
		(property "Manufacturer" "Murata"
			(at 0 0 90)
			(unlocked yes)
			(layer "F.Fab")
			(hide yes)
			(effects
				(font
					(size 1 1)
					(thickness 0.15)
				)
			)
		)
		(property "MPN" "GRM155R61H104KE14D"
			(at 0 0 90)
			(unlocked yes)
			(layer "F.Fab")
			(hide yes)
			(effects
				(font
					(size 1 1)
					(thickness 0.15)
				)
			)
		)
		(property "Val" "100n"
			(at 0 0 90)
			(unlocked yes)
			(layer "F.Fab")
			(hide yes)
			(effects
				(font
					(size 1 1)
					(thickness 0.15)
				)
			)
		)
		(property "License" "Apache-2.0"
			(at 0 0 90)
			(unlocked yes)
			(layer "F.Fab")
			(hide yes)
			(effects
				(font
					(size 1 1)
					(thickness 0.15)
				)
			)
		)
		(property "Author" "Antmicro"
			(at 0 0 90)
			(unlocked yes)
			(layer "F.Fab")
			(hide yes)
			(effects
				(font
					(size 1 1)
					(thickness 0.15)
				)
			)
		)
		(property "Voltage" "50V"
			(at 0 0 90)
			(unlocked yes)
			(layer "F.Fab")
			(hide yes)
			(effects
				(font
					(size 1 1)
					(thickness 0.15)
				)
			)
		)
		(property "Dielectric" "X5R"
			(at 0 0 90)
			(unlocked yes)
			(layer "F.Fab")
			(hide yes)
			(effects
				(font
					(size 1 1)
					(thickness 0.15)
				)
			)
		)
		(sheetname "/Debug FTDI + VNA/")
		(sheetfile "debug-ftdi.kicad_sch")
		(attr smd)
		(fp_rect
			(start -0.925 -0.47)
			(end 0.925 0.47)
			(stroke
				(width 0.05)
				(type default)
			)
			(fill no)
			(layer "F.CrtYd")
		)
		(fp_line
			(start 0.504 -0.25)
			(end 0.504 0.248)
			(stroke
				(width 0.15)
				(type solid)
			)
			(layer "F.Fab")
		)
		(fp_line
			(start -0.494 -0.25)
			(end 0.504 -0.25)
			(stroke
				(width 0.15)
				(type solid)
			)
			(layer "F.Fab")
		)
		(fp_line
			(start 0.504 0.248)
			(end -0.494 0.248)
			(stroke
				(width 0.15)
				(type solid)
			)
			(layer "F.Fab")
		)
		(fp_line
			(start -0.494 0.248)
			(end -0.494 -0.25)
			(stroke
				(width 0.15)
				(type solid)
			)
			(layer "F.Fab")
		)
		(fp_text user "${REFERENCE}"
			(at -0.939 4.599 90)
			(layer "F.Fab")
			(effects
				(font
					(size 0.7 0.7)
					(thickness 0.15)
				)
				(justify left bottom)
			)
		)
		(fp_text user "Author: Antmicro"
			(at -0.939 3.399 90)
			(layer "F.Fab")
			(effects
				(font
					(size 0.7 0.7)
					(thickness 0.15)
				)
				(justify left bottom)
			)
		)
		(fp_text user "License: Apache-2.0"
			(at -0.939 5.799 90)
			(layer "F.Fab")
			(effects
				(font
					(size 0.7 0.7)
					(thickness 0.15)
				)
				(justify left bottom)
			)
		)
		(pad "1" smd roundrect
			(at -0.48 0 90)
			(size 0.59 0.64)
			(layers "F.Cu" "F.Mask" "F.Paste")
			(roundrect_rratio 0.25)
			(net 34 "/Debug FTDI + VNA/FTDI_VCORE")
			(pintype "passive")
		)
		(pad "2" smd roundrect
			(at 0.48 0 90)
			(size 0.59 0.64)
			(layers "F.Cu" "F.Mask" "F.Paste")
			(roundrect_rratio 0.25)
			(net 1 "GND")
			(pintype "passive")
		)
	)
	(footprint "antmicro-footprints:Resonator_SMD_Abracon_ABM8G_3.2x2.5mm"
		(layer "F.Cu")
		(at 135.023 155.374 90)
		(property "Reference" "Y1"
			(at 3.424 -0.723 90)
			(layer "F.SilkS")
			(effects
				(font
					(size 0.7 0.7)
					(thickness 0.15)
				)
				(justify right bottom)
			)
		)
		(property "Value" "Resonator_12MHz_ABM8G"
			(at -1.75 2.548 90)
			(layer "F.Fab")
			(effects
				(font
					(size 0.7 0.7)
					(thickness 0.15)
				)
				(justify left bottom)
			)
		)
		(property "Datasheet" "https://abracon.com/Resonators/ABM8G.pdf"
			(at 0 0 90)
			(layer "F.Fab")
			(hide yes)
			(effects
				(font
					(size 1.27 1.27)
					(thickness 0.15)
				)
			)
		)
		(property "MPN" "ABM8G-12.000MHZ-18-D2Y-T"
			(at 0 0 90)
			(unlocked yes)
			(layer "F.Fab")
			(hide yes)
			(effects
				(font
					(size 1 1)
					(thickness 0.15)
				)
			)
		)
		(property "Manufacturer" "Abracon"
			(at 0 0 90)
			(unlocked yes)
			(layer "F.Fab")
			(hide yes)
			(effects
				(font
					(size 1 1)
					(thickness 0.15)
				)
			)
		)
		(property "Author" "Antmicro"
			(at 0 0 90)
			(unlocked yes)
			(layer "F.Fab")
			(hide yes)
			(effects
				(font
					(size 1 1)
					(thickness 0.15)
				)
			)
		)
		(property "License" "Apache-2.0"
			(at 0 0 90)
			(unlocked yes)
			(layer "F.Fab")
			(hide yes)
			(effects
				(font
					(size 1 1)
					(thickness 0.15)
				)
			)
		)
		(property "Val" "12 MHz"
			(at 0 0 90)
			(unlocked yes)
			(layer "F.Fab")
			(hide yes)
			(effects
				(font
					(size 1 1)
					(thickness 0.15)
				)
			)
		)
		(sheetname "/Debug FTDI + VNA/")
		(sheetfile "debug-ftdi.kicad_sch")
		(attr smd)
		(fp_line
			(start -0.35 -1.25)
			(end 0.45 -1.25)
			(stroke
				(width 0.15)
				(type solid)
			)
			(layer "F.SilkS")
		)
		(fp_line
			(start 1.6 0.3)
			(end 1.6 -0.2)
			(stroke
				(width 0.15)
				(type solid)
			)
			(layer "F.SilkS")
		)
		(fp_line
			(start -1.6 0.3)
			(end -1.6 -0.2)
			(stroke
				(width 0.15)
				(type solid)
			)
			(layer "F.SilkS")
		)
		(fp_line
			(start -0.35 1.25)
			(end 0.45 1.25)
			(stroke
				(width 0.15)
				(type solid)
			)
			(layer "F.SilkS")
		)
		(fp_circle
			(center -1.75 1.5)
			(end -1.7 1.5)
			(stroke
				(width 0.15)
				(type solid)
			)
			(fill no)
			(layer "F.SilkS")
		)
		(fp_rect
			(start -1.907 -1.55)
			(end 2.006 1.649)
			(stroke
				(width 0.05)
				(type solid)
			)
			(fill no)
			(layer "F.CrtYd")
		)
		(fp_text user "${REFERENCE}"
			(at -1.75 3.75 90)
			(layer "F.Fab")
			(effects
				(font
					(size 0.7 0.7)
					(thickness 0.15)
				)
				(justify left bottom)
			)
		)
		(fp_text user "License: Apache-2.0"
			(at -1.75 6.5 90)
			(layer "F.Fab")
			(effects
				(font
					(size 0.7 0.7)
					(thickness 0.15)
				)
				(justify left bottom)
			)
		)
		(fp_text user "Author: Antmicro"
			(at -1.75 5 90)
			(layer "F.Fab")
			(effects
				(font
					(size 0.7 0.7)
					(thickness 0.15)
				)
				(justify left bottom)
			)
		)
		(pad "1" smd roundrect
			(at -1.101 0.949 90)
			(size 1.3 1.1)
			(layers "F.Cu" "F.Mask" "F.Paste")
			(roundrect_rratio 0)
			(chamfer_ratio 0.2)
			(chamfer bottom_left)
			(net 4 "/Debug FTDI + VNA/FTDI_XI")
			(pintype "passive")
		)
		(pad "2" smd rect
			(at 1.199 0.949 90)
			(size 1.3 1.1)
			(layers "F.Cu" "F.Mask" "F.Paste")
			(net 1 "GND")
			(pinfunction "SH")
			(pintype "passive")
		)
		(pad "3" smd rect
			(at 1.199 -0.85 90)
			(size 1.3 1.1)
			(layers "F.Cu" "F.Mask" "F.Paste")
			(net 7 "/Debug FTDI + VNA/FTDI_XO")
			(pintype "passive")
		)
		(pad "4" smd rect
			(at -1.101 -0.85 90)
			(size 1.3 1.1)
			(layers "F.Cu" "F.Mask" "F.Paste")
			(net 1 "GND")
			(pinfunction "SH")
			(pintype "passive")
		)
	)
	(footprint "antmicro-footprints:R_0402_1005Metric"
		(layer "F.Cu")
		(at 149.899499 163.469)
		(descr "Resistor SMD 0402")
		(tags "resistor SMD 0402")
		(property "Reference" "R52"
			(at 0.990501 0.536 0)
			(layer "F.SilkS")
			(effects
				(font
					(size 0.7 0.7)
					(thickness 0.15)
				)
				(justify left bottom)
			)
		)
		(property "Value" "R_22R_0402"
			(at -1.011843 1.772047 0)
			(layer "F.Fab")
			(effects
				(font
					(size 0.7 0.7)
					(thickness 0.15)
				)
				(justify left bottom)
			)
		)
		(property "Datasheet" "https://www.bourns.com/docs/product-datasheets/cr.pdf"
			(at 0 0 0)
			(layer "F.Fab")
			(hide yes)
			(effects
				(font
					(size 1.27 1.27)
					(thickness 0.15)
				)
			)
		)
		(property "Manufacturer" "Bourns"
			(at 0 0 0)
			(unlocked yes)
			(layer "F.Fab")
			(hide yes)
			(effects
				(font
					(size 1 1)
					(thickness 0.15)
				)
			)
		)
		(property "MPN" "CR0402-FX-22R0GLF"
			(at 0 0 0)
			(unlocked yes)
			(layer "F.Fab")
			(hide yes)
			(effects
				(font
					(size 1 1)
					(thickness 0.15)
				)
			)
		)
		(property "Val" "22R"
			(at 0 0 0)
			(unlocked yes)
			(layer "F.Fab")
			(hide yes)
			(effects
				(font
					(size 1 1)
					(thickness 0.15)
				)
			)
		)
		(property "License" "Apache-2.0"
			(at 0 0 0)
			(unlocked yes)
			(layer "F.Fab")
			(hide yes)
			(effects
				(font
					(size 1 1)
					(thickness 0.15)
				)
			)
		)
		(property "Author" "Antmicro"
			(at 0 0 0)
			(unlocked yes)
			(layer "F.Fab")
			(hide yes)
			(effects
				(font
					(size 1 1)
					(thickness 0.15)
				)
			)
		)
		(property "Tolerance" "1%"
			(at 0 0 0)
			(unlocked yes)
			(layer "F.Fab")
			(hide yes)
			(effects
				(font
					(size 1 1)
					(thickness 0.15)
				)
			)
		)
		(sheetname "/Debug FTDI + VNA/")
		(sheetfile "debug-ftdi.kicad_sch")
		(attr smd)
		(fp_rect
			(start -0.925 -0.47)
			(end 0.925 0.47)
			(stroke
				(width 0.05)
				(type default)
			)
			(fill no)
			(layer "F.CrtYd")
		)
		(fp_rect
			(start -0.5 -0.25)
			(end 0.5 0.25)
			(stroke
				(width 0.15)
				(type solid)
			)
			(fill no)
			(layer "F.Fab")
		)
		(fp_text user "${REFERENCE}"
			(at -0.95 3.168 0)
			(layer "F.Fab")
			(effects
				(font
					(size 0.7 0.7)
					(thickness 0.15)
				)
				(justify left bottom)
			)
		)
		(fp_text user "Author: Antmicro"
			(at -0.95 4.169 0)
			(layer "F.Fab")
			(effects
				(font
					(size 0.7 0.7)
					(thickness 0.15)
				)
				(justify left bottom)
			)
		)
		(fp_text user "License: Apache-2.0"
			(at -0.95 5.169 0)
			(layer "F.Fab")
			(effects
				(font
					(size 0.7 0.7)
					(thickness 0.15)
				)
				(justify left bottom)
			)
		)
		(pad "1" smd roundrect
			(at -0.48 0)
			(size 0.59 0.64)
			(layers "F.Cu" "F.Mask" "F.Paste")
			(roundrect_rratio 0.25)
			(net 373 "Net-(U16-B1)")
			(pintype "passive")
		)
		(pad "2" smd roundrect
			(at 0.48 0)
			(size 0.59 0.64)
			(layers "F.Cu" "F.Mask" "F.Paste")
			(roundrect_rratio 0.25)
			(net 374 "/Debug FTDI + VNA/UART0.TX")
			(pintype "passive")
		)
	)
	(footprint "antmicro-footprints:R_0402_1005Metric"
		(layer "F.Cu")
		(at 149.899499 164.494)
		(descr "Resistor SMD 0402")
		(tags "resistor SMD 0402")
		(property "Reference" "R53"
			(at 0.990501 0.536 0)
			(layer "F.SilkS")
			(effects
				(font
					(size 0.7 0.7)
					(thickness 0.15)
				)
				(justify left bottom)
			)
		)
		(property "Value" "R_22R_0402"
			(at -1.011843 1.772047 0)
			(layer "F.Fab")
			(effects
				(font
					(size 0.7 0.7)
					(thickness 0.15)
				)
				(justify left bottom)
			)
		)
		(property "Datasheet" "https://www.bourns.com/docs/product-datasheets/cr.pdf"
			(at 0 0 0)
			(layer "F.Fab")
			(hide yes)
			(effects
				(font
					(size 1.27 1.27)
					(thickness 0.15)
				)
			)
		)
		(property "Manufacturer" "Bourns"
			(at 0 0 0)
			(unlocked yes)
			(layer "F.Fab")
			(hide yes)
			(effects
				(font
					(size 1 1)
					(thickness 0.15)
				)
			)
		)
		(property "MPN" "CR0402-FX-22R0GLF"
			(at 0 0 0)
			(unlocked yes)
			(layer "F.Fab")
			(hide yes)
			(effects
				(font
					(size 1 1)
					(thickness 0.15)
				)
			)
		)
		(property "Val" "22R"
			(at 0 0 0)
			(unlocked yes)
			(layer "F.Fab")
			(hide yes)
			(effects
				(font
					(size 1 1)
					(thickness 0.15)
				)
			)
		)
		(property "License" "Apache-2.0"
			(at 0 0 0)
			(unlocked yes)
			(layer "F.Fab")
			(hide yes)
			(effects
				(font
					(size 1 1)
					(thickness 0.15)
				)
			)
		)
		(property "Author" "Antmicro"
			(at 0 0 0)
			(unlocked yes)
			(layer "F.Fab")
			(hide yes)
			(effects
				(font
					(size 1 1)
					(thickness 0.15)
				)
			)
		)
		(property "Tolerance" "1%"
			(at 0 0 0)
			(unlocked yes)
			(layer "F.Fab")
			(hide yes)
			(effects
				(font
					(size 1 1)
					(thickness 0.15)
				)
			)
		)
		(sheetname "/Debug FTDI + VNA/")
		(sheetfile "debug-ftdi.kicad_sch")
		(attr smd)
		(fp_rect
			(start -0.925 -0.47)
			(end 0.925 0.47)
			(stroke
				(width 0.05)
				(type default)
			)
			(fill no)
			(layer "F.CrtYd")
		)
		(fp_rect
			(start -0.5 -0.25)
			(end 0.5 0.25)
			(stroke
				(width 0.15)
				(type solid)
			)
			(fill no)
			(layer "F.Fab")
		)
		(fp_text user "${REFERENCE}"
			(at -0.95 3.168 0)
			(layer "F.Fab")
			(effects
				(font
					(size 0.7 0.7)
					(thickness 0.15)
				)
				(justify left bottom)
			)
		)
		(fp_text user "License: Apache-2.0"
			(at -0.95 5.169 0)
			(layer "F.Fab")
			(effects
				(font
					(size 0.7 0.7)
					(thickness 0.15)
				)
				(justify left bottom)
			)
		)
		(fp_text user "Author: Antmicro"
			(at -0.95 4.169 0)
			(layer "F.Fab")
			(effects
				(font
					(size 0.7 0.7)
					(thickness 0.15)
				)
				(justify left bottom)
			)
		)
		(pad "1" smd roundrect
			(at -0.48 0)
			(size 0.59 0.64)
			(layers "F.Cu" "F.Mask" "F.Paste")
			(roundrect_rratio 0.25)
			(net 375 "Net-(U16-B2)")
			(pintype "passive")
		)
		(pad "2" smd roundrect
			(at 0.48 0)
			(size 0.59 0.64)
			(layers "F.Cu" "F.Mask" "F.Paste")
			(roundrect_rratio 0.25)
			(net 376 "/Debug FTDI + VNA/UART0.RX")
			(pintype "passive")
		)
	)
)
